(kicad_pcb
	(version 20260206)
	(generator "pcbnew")
	(generator_version "10.0")
	(general
		(thickness 1.6)
		(legacy_teardrops no)
	)
	(paper "A4")
	(title_block
		(title "v1-pdb — T6M_PDB_D_0927_0900.brd")
		(comment 1 "Open CloudServer (Microsoft) / footprint 239 of 321 (J26), pads 79-156 of 166")
	)
	(layers
		(0 "F.Cu" signal "TOP")
		(4 "In1.Cu" signal "GND")
		(6 "In2.Cu" signal "IN1")
		(8 "In3.Cu" signal "VCC")
		(10 "In4.Cu" signal "VCC1")
		(12 "In5.Cu" signal "IN2")
		(14 "In6.Cu" signal "GND1")
		(2 "B.Cu" signal "BOTTOM")
		(9 "F.Adhes" user "F.Adhesive")
		(11 "B.Adhes" user "B.Adhesive")
		(13 "F.Paste" user "Package Geometry/Pastemask Top")
		(15 "B.Paste" user "Package Geometry/Pastemask Bottom")
		(5 "F.SilkS" user "Ref Des/Silkscreen Top")
		(7 "B.SilkS" user "Ref Des/Silkscreen Bottom")
		(1 "F.Mask" user "Board Geometry/Soldermask Top")
		(3 "B.Mask" user "Board Geometry/Soldermask Bottom")
		(17 "Dwgs.User" user "User.Drawings")
		(19 "Cmts.User" user "User.Comments")
		(21 "Eco1.User" user "User.Eco1")
		(23 "Eco2.User" user "User.Eco2")
		(25 "Edge.Cuts" user "Board Geometry/Outline")
		(27 "Margin" user)
		(31 "F.CrtYd" user "Package Geometry/Place Bound Top")
		(29 "B.CrtYd" user "Package Geometry/Place Bound Bottom")
		(35 "F.Fab" user "Ref Des/Assembly Top")
		(33 "B.Fab" user "Ref Des/Assembly Bottom")
	)
	(footprint ""
		(layer "F.Cu")
		(at 6.448806 -261.670546)
		(property "Reference" "J26"
			(at 6.660642 8.995918 90)
			(unlocked yes)
			(layer "F.SilkS")
			(effects
				(font
					(size 0.7874 0.5842)
					(thickness 0.1524)
				)
				(justify left)
			)
		)
		(property "Value" ""
			(at 0 0 0)
			(layer "F.Fab")
			(effects
				(font
					(size 1.27 1.27)
				)
			)
		)
		(duplicate_pad_numbers_are_jumpers no)
		(pad "A77" thru_hole circle
			(at 0 78.000098 270)
			(size 1.016 1.016)
			(drill 0.7112)
			(layers "*.Cu" "*.Mask")
			(remove_unused_layers no)
			(net "GND")
			(clearance 0.1016)
			(thermal_gap 0.1016)
		)
		(pad "A78" thru_hole circle
			(at 1.999996 79.000096 270)
			(size 1.016 1.016)
			(drill 0.7112)
			(layers "*.Cu" "*.Mask")
			(remove_unused_layers no)
			(net "P12V")
			(clearance 0.1016)
			(thermal_gap 0.1016)
		)
		(pad "A79" thru_hole circle
			(at 0 80.000094 270)
			(size 1.016 1.016)
			(drill 0.7112)
			(layers "*.Cu" "*.Mask")
			(remove_unused_layers no)
			(net "P12V")
			(clearance 0.1016)
			(thermal_gap 0.1016)
		)
		(pad "A80" thru_hole circle
			(at 1.999996 81.000092 270)
			(size 1.016 1.016)
			(drill 0.7112)
			(layers "*.Cu" "*.Mask")
			(remove_unused_layers no)
			(net "P12V")
			(clearance 0.1016)
			(thermal_gap 0.1016)
		)
		(pad "A81" thru_hole circle
			(at 0 82.00009 270)
			(size 1.016 1.016)
			(drill 0.7112)
			(layers "*.Cu" "*.Mask")
			(remove_unused_layers no)
			(net "P12V")
			(clearance 0.1016)
			(thermal_gap 0.1016)
		)
		(pad "A82" thru_hole circle
			(at 1.999996 83.000088 270)
			(size 1.016 1.016)
			(drill 0.7112)
			(layers "*.Cu" "*.Mask")
			(remove_unused_layers no)
			(net "P12V")
			(clearance 0.1016)
			(thermal_gap 0.1016)
		)
		(pad "B1" thru_hole circle
			(at -2.499868 0 270)
			(size 1.016 1.016)
			(drill 0.7112)
			(layers "*.Cu" "*.Mask")
			(remove_unused_layers no)
			(net "GND")
			(clearance 0.1016)
			(thermal_gap 0.1016)
		)
		(pad "B2" thru_hole circle
			(at -4.499864 0.999998 270)
			(size 1.016 1.016)
			(drill 0.7112)
			(layers "*.Cu" "*.Mask")
			(remove_unused_layers no)
			(net "T6_BLAD2_RXD")
			(clearance 0.1016)
			(thermal_gap 0.1016)
		)
		(pad "B3" thru_hole circle
			(at -2.499868 1.999996 270)
			(size 1.016 1.016)
			(drill 0.7112)
			(layers "*.Cu" "*.Mask")
			(remove_unused_layers no)
			(net "T6_BLAD2_TXD")
			(clearance 0.1016)
			(thermal_gap 0.1016)
		)
		(pad "B4" thru_hole circle
			(at -4.499864 2.999994 270)
			(size 1.016 1.016)
			(drill 0.7112)
			(layers "*.Cu" "*.Mask")
			(remove_unused_layers no)
			(net "GND")
			(clearance 0.1016)
			(thermal_gap 0.1016)
		)
		(pad "B5" thru_hole circle
			(at -2.499868 3.999992 270)
			(size 1.016 1.016)
			(drill 0.7112)
			(layers "*.Cu" "*.Mask")
			(remove_unused_layers no)
			(net "T6_BLAD3_RXD")
			(clearance 0.1016)
			(thermal_gap 0.1016)
		)
		(pad "B6" thru_hole circle
			(at -4.499864 4.99999 270)
			(size 1.016 1.016)
			(drill 0.7112)
			(layers "*.Cu" "*.Mask")
			(remove_unused_layers no)
			(net "T6_BLAD3_TXD")
			(clearance 0.1016)
			(thermal_gap 0.1016)
		)
		(pad "B7" thru_hole circle
			(at -2.499868 5.999988 270)
			(size 1.016 1.016)
			(drill 0.7112)
			(layers "*.Cu" "*.Mask")
			(remove_unused_layers no)
			(net "T6_BLAD4_RXD")
			(clearance 0.1016)
			(thermal_gap 0.1016)
		)
		(pad "B8" thru_hole circle
			(at -4.499864 6.999986 270)
			(size 1.016 1.016)
			(drill 0.7112)
			(layers "*.Cu" "*.Mask")
			(remove_unused_layers no)
			(net "T6_BLAD4_TXD")
			(clearance 0.1016)
			(thermal_gap 0.1016)
		)
		(pad "B9" thru_hole circle
			(at -2.499868 7.999984 270)
			(size 1.016 1.016)
			(drill 0.7112)
			(layers "*.Cu" "*.Mask")
			(remove_unused_layers no)
			(net "GND")
			(clearance 0.1016)
			(thermal_gap 0.1016)
		)
		(pad "B10" thru_hole circle
			(at -4.499864 8.999982 270)
			(size 1.016 1.016)
			(drill 0.7112)
			(layers "*.Cu" "*.Mask")
			(remove_unused_layers no)
			(net "I2C_PSU2_SCL")
			(clearance 0.1016)
			(thermal_gap 0.1016)
		)
		(pad "B11" thru_hole circle
			(at -2.499868 9.99998 270)
			(size 1.016 1.016)
			(drill 0.7112)
			(layers "*.Cu" "*.Mask")
			(remove_unused_layers no)
			(net "I2C_PSU2_SDA")
			(clearance 0.1016)
			(thermal_gap 0.1016)
		)
		(pad "B12" thru_hole circle
			(at -4.499864 12.999974 270)
			(size 1.016 1.016)
			(drill 0.7112)
			(layers "*.Cu" "*.Mask")
			(remove_unused_layers no)
			(net "T4_BLAD1_EN")
			(clearance 0.1016)
			(thermal_gap 0.1016)
		)
		(pad "B13" thru_hole circle
			(at -2.499868 13.999972 270)
			(size 1.016 1.016)
			(drill 0.7112)
			(layers "*.Cu" "*.Mask")
			(remove_unused_layers no)
			(net "T4_BLAD2_EN")
			(clearance 0.1016)
			(thermal_gap 0.1016)
		)
		(pad "B14" thru_hole circle
			(at -4.499864 14.99997 270)
			(size 1.016 1.016)
			(drill 0.7112)
			(layers "*.Cu" "*.Mask")
			(remove_unused_layers no)
			(net "T4_BLAD3_EN")
			(clearance 0.1016)
			(thermal_gap 0.1016)
		)
		(pad "B15" thru_hole circle
			(at -2.499868 15.999968 270)
			(size 1.016 1.016)
			(drill 0.7112)
			(layers "*.Cu" "*.Mask")
			(remove_unused_layers no)
			(net "T4_BLAD4_EN")
			(clearance 0.1016)
			(thermal_gap 0.1016)
		)
		(pad "B16" thru_hole circle
			(at -4.499864 16.999966 270)
			(size 1.016 1.016)
			(drill 0.7112)
			(layers "*.Cu" "*.Mask")
			(remove_unused_layers no)
			(net "GND")
			(clearance 0.1016)
			(thermal_gap 0.1016)
		)
		(pad "B17" thru_hole circle
			(at -2.499868 17.999964 270)
			(size 1.016 1.016)
			(drill 0.7112)
			(layers "*.Cu" "*.Mask")
			(remove_unused_layers no)
			(net "T4_BLAD1_RXD")
			(clearance 0.1016)
			(thermal_gap 0.1016)
		)
		(pad "B18" thru_hole circle
			(at -4.499864 18.999962 270)
			(size 1.016 1.016)
			(drill 0.7112)
			(layers "*.Cu" "*.Mask")
			(remove_unused_layers no)
			(net "T4_BLAD1_TXD")
			(clearance 0.1016)
			(thermal_gap 0.1016)
		)
		(pad "B19" thru_hole circle
			(at -2.499868 19.99996 270)
			(size 1.016 1.016)
			(drill 0.7112)
			(layers "*.Cu" "*.Mask")
			(remove_unused_layers no)
			(net "T4_BLAD2_RXD")
			(clearance 0.1016)
			(thermal_gap 0.1016)
		)
		(pad "B20" thru_hole circle
			(at -4.499864 20.999958 270)
			(size 1.016 1.016)
			(drill 0.7112)
			(layers "*.Cu" "*.Mask")
			(remove_unused_layers no)
			(net "T4_BLAD2_TXD")
			(clearance 0.1016)
			(thermal_gap 0.1016)
		)
		(pad "B21" thru_hole circle
			(at -2.499868 21.999956 270)
			(size 1.016 1.016)
			(drill 0.7112)
			(layers "*.Cu" "*.Mask")
			(remove_unused_layers no)
			(net "GND")
			(clearance 0.1016)
			(thermal_gap 0.1016)
		)
		(pad "B22" thru_hole circle
			(at -4.499864 22.999954 270)
			(size 1.016 1.016)
			(drill 0.7112)
			(layers "*.Cu" "*.Mask")
			(remove_unused_layers no)
			(net "T4_BLAD3_RXD")
			(clearance 0.1016)
			(thermal_gap 0.1016)
		)
		(pad "B23" thru_hole circle
			(at -2.499868 23.999952 270)
			(size 1.016 1.016)
			(drill 0.7112)
			(layers "*.Cu" "*.Mask")
			(remove_unused_layers no)
			(net "T4_BLAD3_TXD")
			(clearance 0.1016)
			(thermal_gap 0.1016)
		)
		(pad "B24" thru_hole circle
			(at -4.499864 24.99995 270)
			(size 1.016 1.016)
			(drill 0.7112)
			(layers "*.Cu" "*.Mask")
			(remove_unused_layers no)
			(net "T4_BLAD4_RXD")
			(clearance 0.1016)
			(thermal_gap 0.1016)
		)
		(pad "B25" thru_hole circle
			(at -2.499868 25.999948 270)
			(size 1.016 1.016)
			(drill 0.7112)
			(layers "*.Cu" "*.Mask")
			(remove_unused_layers no)
			(net "T4_BLAD4_TXD")
			(clearance 0.1016)
			(thermal_gap 0.1016)
		)
		(pad "B26" thru_hole circle
			(at -4.499864 26.999946 270)
			(size 1.016 1.016)
			(drill 0.7112)
			(layers "*.Cu" "*.Mask")
			(remove_unused_layers no)
			(net "GND")
			(clearance 0.1016)
			(thermal_gap 0.1016)
		)
		(pad "B27" thru_hole circle
			(at -2.499868 27.999944 270)
			(size 1.016 1.016)
			(drill 0.7112)
			(layers "*.Cu" "*.Mask")
			(remove_unused_layers no)
			(net "T2_BLAD1_EN")
			(clearance 0.1016)
			(thermal_gap 0.1016)
		)
		(pad "B28" thru_hole circle
			(at -4.499864 28.999942 270)
			(size 1.016 1.016)
			(drill 0.7112)
			(layers "*.Cu" "*.Mask")
			(remove_unused_layers no)
			(net "T2_BLAD2_EN")
			(clearance 0.1016)
			(thermal_gap 0.1016)
		)
		(pad "B29" thru_hole circle
			(at -2.499868 29.99994 270)
			(size 1.016 1.016)
			(drill 0.7112)
			(layers "*.Cu" "*.Mask")
			(remove_unused_layers no)
			(net "T2_BLAD3_EN")
			(clearance 0.1016)
			(thermal_gap 0.1016)
		)
		(pad "B30" thru_hole circle
			(at -4.499864 30.999938 270)
			(size 1.016 1.016)
			(drill 0.7112)
			(layers "*.Cu" "*.Mask")
			(remove_unused_layers no)
			(net "T2_BLAD4_EN")
			(clearance 0.1016)
			(thermal_gap 0.1016)
		)
		(pad "B31" thru_hole circle
			(at -2.499868 31.999936 270)
			(size 1.016 1.016)
			(drill 0.7112)
			(layers "*.Cu" "*.Mask")
			(remove_unused_layers no)
			(net "GND")
			(clearance 0.1016)
			(thermal_gap 0.1016)
		)
		(pad "B32" thru_hole circle
			(at -4.499864 32.999934 270)
			(size 1.016 1.016)
			(drill 0.7112)
			(layers "*.Cu" "*.Mask")
			(remove_unused_layers no)
			(net "T2_BLAD1_RXD")
			(clearance 0.1016)
			(thermal_gap 0.1016)
		)
		(pad "B33" thru_hole circle
			(at -2.499868 33.999932 270)
			(size 1.016 1.016)
			(drill 0.7112)
			(layers "*.Cu" "*.Mask")
			(remove_unused_layers no)
			(net "T2_BLAD1_TXD")
			(clearance 0.1016)
			(thermal_gap 0.1016)
		)
		(pad "B34" thru_hole circle
			(at -4.499864 34.99993 270)
			(size 1.016 1.016)
			(drill 0.7112)
			(layers "*.Cu" "*.Mask")
			(remove_unused_layers no)
			(net "T2_BLAD2_RXD")
			(clearance 0.1016)
			(thermal_gap 0.1016)
		)
		(pad "B35" thru_hole circle
			(at -2.499868 35.999928 270)
			(size 1.016 1.016)
			(drill 0.7112)
			(layers "*.Cu" "*.Mask")
			(remove_unused_layers no)
			(net "T2_BLAD2_TXD")
			(clearance 0.1016)
			(thermal_gap 0.1016)
		)
		(pad "B36" thru_hole circle
			(at -4.499864 36.999926 270)
			(size 1.016 1.016)
			(drill 0.7112)
			(layers "*.Cu" "*.Mask")
			(remove_unused_layers no)
			(net "GND")
			(clearance 0.1016)
			(thermal_gap 0.1016)
		)
		(pad "B37" thru_hole circle
			(at -2.499868 37.999924 270)
			(size 1.016 1.016)
			(drill 0.7112)
			(layers "*.Cu" "*.Mask")
			(remove_unused_layers no)
			(net "T2_BLAD3_RXD")
			(clearance 0.1016)
			(thermal_gap 0.1016)
		)
		(pad "B38" thru_hole circle
			(at -4.499864 38.999922 270)
			(size 1.016 1.016)
			(drill 0.7112)
			(layers "*.Cu" "*.Mask")
			(remove_unused_layers no)
			(net "T2_BLAD3_TXD")
			(clearance 0.1016)
			(thermal_gap 0.1016)
		)
		(pad "B39" thru_hole circle
			(at -2.499868 39.99992 270)
			(size 1.016 1.016)
			(drill 0.7112)
			(layers "*.Cu" "*.Mask")
			(remove_unused_layers no)
			(net "T2_BLAD4_RXD")
			(clearance 0.1016)
			(thermal_gap 0.1016)
		)
		(pad "B40" thru_hole circle
			(at -4.499864 40.999918 270)
			(size 1.016 1.016)
			(drill 0.7112)
			(layers "*.Cu" "*.Mask")
			(remove_unused_layers no)
			(net "T2_BLAD4_TXD")
			(clearance 0.1016)
			(thermal_gap 0.1016)
		)
		(pad "B41" thru_hole circle
			(at -2.499868 41.999916 270)
			(size 1.016 1.016)
			(drill 0.7112)
			(layers "*.Cu" "*.Mask")
			(remove_unused_layers no)
			(net "GND")
			(clearance 0.1016)
			(thermal_gap 0.1016)
		)
		(pad "B42" thru_hole circle
			(at -4.499864 42.999914 270)
			(size 1.016 1.016)
			(drill 0.7112)
			(layers "*.Cu" "*.Mask")
			(remove_unused_layers no)
			(net "I2C_PSU1_SCL")
			(clearance 0.1016)
			(thermal_gap 0.1016)
		)
		(pad "B43" thru_hole circle
			(at -2.499868 43.999912 270)
			(size 1.016 1.016)
			(drill 0.7112)
			(layers "*.Cu" "*.Mask")
			(remove_unused_layers no)
			(net "I2C_PSU1_SDA")
			(clearance 0.1016)
			(thermal_gap 0.1016)
		)
		(pad "B44" thru_hole circle
			(at -4.499864 44.99991 270)
			(size 1.016 1.016)
			(drill 0.7112)
			(layers "*.Cu" "*.Mask")
			(remove_unused_layers no)
			(net "GND")
			(clearance 0.1016)
			(thermal_gap 0.1016)
		)
		(pad "B45" thru_hole circle
			(at -2.499868 45.999908 270)
			(size 1.016 1.016)
			(drill 0.7112)
			(layers "*.Cu" "*.Mask")
			(remove_unused_layers no)
			(net "PSU1_AC_OK")
			(clearance 0.1016)
			(thermal_gap 0.1016)
		)
		(pad "B46" thru_hole circle
			(at -4.499864 46.999906 270)
			(size 1.016 1.016)
			(drill 0.7112)
			(layers "*.Cu" "*.Mask")
			(remove_unused_layers no)
			(net "PSU2_AC_OK")
			(clearance 0.1016)
			(thermal_gap 0.1016)
		)
		(pad "B47" thru_hole circle
			(at -2.499868 47.999904 270)
			(size 1.016 1.016)
			(drill 0.7112)
			(layers "*.Cu" "*.Mask")
			(remove_unused_layers no)
			(net "PSU3_AC_OK")
			(clearance 0.1016)
			(thermal_gap 0.1016)
		)
		(pad "B48" thru_hole circle
			(at -4.499864 48.999902 270)
			(size 1.016 1.016)
			(drill 0.7112)
			(layers "*.Cu" "*.Mask")
			(remove_unused_layers no)
			(net "PSU4_AC_OK")
			(clearance 0.1016)
			(thermal_gap 0.1016)
		)
		(pad "B49" thru_hole circle
			(at -2.499868 49.9999 270)
			(size 1.016 1.016)
			(drill 0.7112)
			(layers "*.Cu" "*.Mask")
			(remove_unused_layers no)
			(net "PSU5_AC_OK")
			(clearance 0.1016)
			(thermal_gap 0.1016)
		)
		(pad "B50" thru_hole circle
			(at -4.499864 50.999898 270)
			(size 1.016 1.016)
			(drill 0.7112)
			(layers "*.Cu" "*.Mask")
			(remove_unused_layers no)
			(net "PSU6_AC_OK")
			(clearance 0.1016)
			(thermal_gap 0.1016)
		)
		(pad "B51" thru_hole circle
			(at -2.499868 51.999896 270)
			(size 1.016 1.016)
			(drill 0.7112)
			(layers "*.Cu" "*.Mask")
			(remove_unused_layers no)
			(net "GND")
			(clearance 0.1016)
			(thermal_gap 0.1016)
		)
		(pad "B52" thru_hole circle
			(at -4.499864 52.999894 270)
			(size 1.016 1.016)
			(drill 0.7112)
			(layers "*.Cu" "*.Mask")
			(remove_unused_layers no)
			(net "UART_RTS_P5_L_N")
			(clearance 0.1016)
			(thermal_gap 0.1016)
		)
		(pad "B53" thru_hole circle
			(at -2.499868 53.999892 270)
			(size 1.016 1.016)
			(drill 0.7112)
			(layers "*.Cu" "*.Mask")
			(remove_unused_layers no)
			(net "UART_DSR_P5_L_N")
			(clearance 0.1016)
			(thermal_gap 0.1016)
		)
		(pad "B54" thru_hole circle
			(at -4.499864 54.99989 270)
			(size 1.016 1.016)
			(drill 0.7112)
			(layers "*.Cu" "*.Mask")
			(remove_unused_layers no)
			(net "UART_RX_P5_L")
			(clearance 0.1016)
			(thermal_gap 0.1016)
		)
		(pad "B55" thru_hole circle
			(at -2.499868 55.999888 270)
			(size 1.016 1.016)
			(drill 0.7112)
			(layers "*.Cu" "*.Mask")
			(remove_unused_layers no)
			(net "UART_TX_P5_L")
			(clearance 0.1016)
			(thermal_gap 0.1016)
		)
		(pad "B56" thru_hole circle
			(at -4.499864 56.999886 270)
			(size 1.016 1.016)
			(drill 0.7112)
			(layers "*.Cu" "*.Mask")
			(remove_unused_layers no)
			(net "UART_DTR_P5_L_N")
			(clearance 0.1016)
			(thermal_gap 0.1016)
		)
		(pad "B57" thru_hole circle
			(at -2.499868 57.999884 270)
			(size 1.016 1.016)
			(drill 0.7112)
			(layers "*.Cu" "*.Mask")
			(remove_unused_layers no)
			(net "UART_CTS_P5_L_N")
			(clearance 0.1016)
			(thermal_gap 0.1016)
		)
		(pad "B58" thru_hole circle
			(at -4.499864 59.000136 270)
			(size 1.016 1.016)
			(drill 0.7112)
			(layers "*.Cu" "*.Mask")
			(remove_unused_layers no)
			(net "UART_RI_P5_L_N")
			(clearance 0.1016)
			(thermal_gap 0.1016)
		)
		(pad "B59" thru_hole circle
			(at -2.499868 59.99988 270)
			(size 1.016 1.016)
			(drill 0.7112)
			(layers "*.Cu" "*.Mask")
			(remove_unused_layers no)
			(net "GND")
			(clearance 0.1016)
			(thermal_gap 0.1016)
		)
		(pad "B60" thru_hole circle
			(at -4.499864 61.000132 270)
			(size 1.016 1.016)
			(drill 0.7112)
			(layers "*.Cu" "*.Mask")
			(remove_unused_layers no)
			(net "UART_RTS_P1_L_N")
			(clearance 0.1016)
			(thermal_gap 0.1016)
		)
		(pad "B61" thru_hole circle
			(at -2.499868 61.999876 270)
			(size 1.016 1.016)
			(drill 0.7112)
			(layers "*.Cu" "*.Mask")
			(remove_unused_layers no)
			(net "UART_DSR_P1_L_N")
			(clearance 0.1016)
			(thermal_gap 0.1016)
		)
		(pad "B62" thru_hole circle
			(at -4.499864 63.000128 270)
			(size 1.016 1.016)
			(drill 0.7112)
			(layers "*.Cu" "*.Mask")
			(remove_unused_layers no)
			(net "UART_RX_P1_L")
			(clearance 0.1016)
			(thermal_gap 0.1016)
		)
		(pad "B63" thru_hole circle
			(at -2.499868 63.999872 270)
			(size 1.016 1.016)
			(drill 0.7112)
			(layers "*.Cu" "*.Mask")
			(remove_unused_layers no)
			(net "UART_TX_P1_L")
			(clearance 0.1016)
			(thermal_gap 0.1016)
		)
		(pad "B64" thru_hole circle
			(at -4.499864 65.000124 270)
			(size 1.016 1.016)
			(drill 0.7112)
			(layers "*.Cu" "*.Mask")
			(remove_unused_layers no)
			(net "UART_DTR_P1_L_N")
			(clearance 0.1016)
			(thermal_gap 0.1016)
		)
		(pad "B65" thru_hole circle
			(at -2.499868 65.999868 270)
			(size 1.016 1.016)
			(drill 0.7112)
			(layers "*.Cu" "*.Mask")
			(remove_unused_layers no)
			(net "UART_CTS_P1_L_N")
			(clearance 0.1016)
			(thermal_gap 0.1016)
		)
		(pad "B66" thru_hole circle
			(at -4.499864 67.00012 270)
			(size 1.016 1.016)
			(drill 0.7112)
			(layers "*.Cu" "*.Mask")
			(remove_unused_layers no)
			(net "GND")
			(clearance 0.1016)
			(thermal_gap 0.1016)
		)
		(pad "B67" thru_hole circle
			(at -2.499868 67.999864 270)
			(size 1.016 1.016)
			(drill 0.7112)
			(layers "*.Cu" "*.Mask")
			(remove_unused_layers no)
			(net "Net_411")
			(clearance 0.1016)
			(thermal_gap 0.1016)
		)
		(pad "B68" thru_hole circle
			(at -4.499864 69.000116 270)
			(size 1.016 1.016)
			(drill 0.7112)
			(layers "*.Cu" "*.Mask")
			(remove_unused_layers no)
			(net "GND28")
			(clearance 0.1016)
			(thermal_gap 0.1016)
		)
		(pad "B69" thru_hole circle
			(at -2.499868 70.000114 270)
			(size 1.016 1.016)
			(drill 0.7112)
			(layers "*.Cu" "*.Mask")
			(remove_unused_layers no)
			(net "GND29")
			(clearance 0.1016)
			(thermal_gap 0.1016)
		)
		(pad "B70" thru_hole circle
			(at -4.499864 71.000112 270)
			(size 1.016 1.016)
			(drill 0.7112)
			(layers "*.Cu" "*.Mask")
			(remove_unused_layers no)
			(net "Net_410")
			(clearance 0.1016)
			(thermal_gap 0.1016)
		)
		(pad "B71" thru_hole circle
			(at -2.499868 72.00011 270)
			(size 1.016 1.016)
			(drill 0.7112)
			(layers "*.Cu" "*.Mask")
			(remove_unused_layers no)
			(net "GND")
			(clearance 0.1016)
			(thermal_gap 0.1016)
		)
		(pad "B72" thru_hole circle
			(at -4.499864 73.000108 270)
			(size 1.016 1.016)
			(drill 0.7112)
			(layers "*.Cu" "*.Mask")
			(remove_unused_layers no)
			(net "LAN1_P3_P")
			(clearance 0.1016)
			(thermal_gap 0.1016)
		)
	)
)
